# T6G (Grand Teton) — schematic netlist excerpt (pin names and nets, part order shuffled) for the footprints in the layout excerpt that follows; sources: Cadence DE-HDL packaged netlist, KiCad conversion of 04192023_DAF0TMB3IC0_F0TG_MB_C_brd_V02_OCP.brd

R1100  Q_RES  20K 1% CHIP  pkg 0201LF  page 309 : A = RT_CPU0_P3_ADDR2 ; B = GND

U271  LM75BD  IC  pkg SO8_1-27_4-9X3-9  page 235
  SDA  = SMB_LM75_1_3V3AUX_SDA_R1
  SCL  = SMB_LM75_1_3V3AUX_SCL_R1
  OS  = FM_G751_1_ALERT_N
  GND  = GND
  A2  = U271_1_ADD2
  A1  = U271_1_ADD1
  A0  = U271_1_ADD0
  VCC  = P3V3_AUX

R1270  Q_RES  0 5% CHIP  pkg 0402LF  page 357 : A = P12V_OCP_SFF_ADC_ALERT_R ; B = OCP_SFF_P3V3_P12V_ADC_R_ALERT

(kicad_pcb
	(version 20260206)
	(generator "pcbnew")
	(generator_version "10.0")
	(general
		(thickness 1.6)
		(legacy_teardrops no)
	)
	(paper "A4")
	(title_block
		(title "04192023_DAF0TMB3IC0_F0TG_MB_C_brd_V02_OCP.brd")
		(comment 1 "Grand Teton / footprints 9-11 of 8354")
	)
	(layers
		(0 "F.Cu" signal "TOP")
		(4 "In1.Cu" signal "GND")
		(6 "In2.Cu" signal "IN1")
		(8 "In3.Cu" signal "GND1")
		(10 "In4.Cu" signal "IN2")
		(12 "In5.Cu" signal "GND2")
		(14 "In6.Cu" signal "IN3")
		(16 "In7.Cu" signal "GND3")
		(18 "In8.Cu" signal "VCC")
		(20 "In9.Cu" signal "VCC1")
		(22 "In10.Cu" signal "GND4")
		(24 "In11.Cu" signal "IN4")
		(26 "In12.Cu" signal "GND5")
		(28 "In13.Cu" signal "IN5")
		(30 "In14.Cu" signal "GND6")
		(32 "In15.Cu" signal "IN6")
		(34 "In16.Cu" signal "GND7")
		(2 "B.Cu" signal "BOTTOM")
		(9 "F.Adhes" user "F.Adhesive")
		(11 "B.Adhes" user "B.Adhesive")
		(13 "F.Paste" user "Package Geometry/Pastemask Top")
		(15 "B.Paste" user "Package Geometry/Pastemask Bottom")
		(5 "F.SilkS" user "Ref Des/Silkscreen Top")
		(7 "B.SilkS" user "Ref Des/Silkscreen Bottom")
		(1 "F.Mask" user "Board Geometry/Soldermask Top")
		(3 "B.Mask" user "Board Geometry/Soldermask Bottom")
		(17 "Dwgs.User" user "User.Drawings")
		(19 "Cmts.User" user "User.Comments")
		(21 "Eco1.User" user "User.Eco1")
		(23 "Eco2.User" user "User.Eco2")
		(25 "Edge.Cuts" user "Board Geometry/Outline")
		(27 "Margin" user)
		(31 "F.CrtYd" user "Package Geometry/Place Bound Top")
		(29 "B.CrtYd" user "Package Geometry/Place Bound Bottom")
		(35 "F.Fab" user "Ref Des/Assembly Top")
		(33 "B.Fab" user "Ref Des/Assembly Bottom")
	)
	(footprint ""
		(layer "F.Cu")
		(at 294.365426 -15.414244)
		(property "Reference" "U271"
			(at 3.60934 -2.106168 0)
			(unlocked yes)
			(layer "F.SilkS")
			(effects
				(font
					(size 0.7874 0.5842)
					(thickness 0.1524)
				)
				(justify left)
			)
		)
		(property "Value" ""
			(at 0 0 0)
			(layer "F.Fab")
			(effects
				(font
					(size 1.27 1.27)
				)
			)
		)
		(duplicate_pad_numbers_are_jumpers no)
		(fp_line
			(start -3.447796 -2.500122)
			(end -3.447796 2.500122)
			(stroke
				(width 0.1524)
				(type default)
			)
			(layer "F.SilkS")
		)
		(fp_line
			(start -3.447796 2.500122)
			(end 3.447796 2.500122)
			(stroke
				(width 0.1524)
				(type default)
			)
			(layer "F.SilkS")
		)
		(fp_line
			(start -1.484122 -2.500122)
			(end -3.447796 -2.500122)
			(stroke
				(width 0.1524)
				(type default)
			)
			(layer "F.SilkS")
		)
		(fp_line
			(start 0 -1.016)
			(end -1.484122 -2.500122)
			(stroke
				(width 0.1524)
				(type default)
			)
			(layer "F.SilkS")
		)
		(fp_line
			(start 1.484122 -2.500122)
			(end 0 -1.016)
			(stroke
				(width 0.1524)
				(type default)
			)
			(layer "F.SilkS")
		)
		(fp_line
			(start 3.447796 -2.500122)
			(end 1.484122 -2.500122)
			(stroke
				(width 0.1524)
				(type default)
			)
			(layer "F.SilkS")
		)
		(fp_line
			(start 3.447796 2.500122)
			(end 3.447796 -2.500122)
			(stroke
				(width 0.1524)
				(type default)
			)
			(layer "F.SilkS")
		)
		(fp_poly
			(pts
				(xy -4.5974 -1.397) (xy -4.5974 -2.413) (xy -3.5814 -1.905)
			)
			(stroke
				(width 0)
				(type default)
			)
			(fill yes)
			(layer "F.SilkS")
		)
		(fp_line
			(start -1.999996 -2.500122)
			(end -1.999996 2.500122)
			(stroke
				(width 0.1)
				(type default)
			)
			(layer "F.Fab")
		)
		(fp_line
			(start -1.999996 2.500122)
			(end 1.999996 2.500122)
			(stroke
				(width 0.1)
				(type default)
			)
			(layer "F.Fab")
		)
		(fp_line
			(start 1.999996 -2.500122)
			(end -1.999996 -2.500122)
			(stroke
				(width 0.1)
				(type default)
			)
			(layer "F.Fab")
		)
		(fp_line
			(start 1.999996 2.500122)
			(end 1.999996 -2.500122)
			(stroke
				(width 0.1)
				(type default)
			)
			(layer "F.Fab")
		)
		(fp_poly
			(pts
				(xy -4.5974 -2.413) (xy -4.5974 -1.397) (xy -3.5814 -1.905)
			)
			(stroke
				(width 0)
				(type default)
			)
			(fill yes)
			(layer "F.Fab")
		)
		(pad "1" smd rect
			(at -2.649982 -1.905 270)
			(size 0.6096 1.3208)
			(layers "F.Cu" "F.Mask" "F.Paste")
			(net "SMB_LM75_1_3V3AUX_SDA_R1")
		)
		(pad "2" smd rect
			(at -2.649982 -0.635 270)
			(size 0.6096 1.3208)
			(layers "F.Cu" "F.Mask" "F.Paste")
			(net "SMB_LM75_1_3V3AUX_SCL_R1")
		)
		(pad "3" smd rect
			(at -2.649982 0.635 270)
			(size 0.6096 1.3208)
			(layers "F.Cu" "F.Mask" "F.Paste")
			(net "FM_G751_1_ALERT_N")
		)
		(pad "4" smd rect
			(at -2.649982 1.905 270)
			(size 0.6096 1.3208)
			(layers "F.Cu" "F.Mask" "F.Paste")
			(net "GND")
		)
		(pad "5" smd rect
			(at 2.649982 1.905 270)
			(size 0.6096 1.3208)
			(layers "F.Cu" "F.Mask" "F.Paste")
			(net "U271_1_ADD2")
		)
		(pad "6" smd rect
			(at 2.649982 0.635 270)
			(size 0.6096 1.3208)
			(layers "F.Cu" "F.Mask" "F.Paste")
			(net "U271_1_ADD1")
		)
		(pad "7" smd rect
			(at 2.649982 -0.635 270)
			(size 0.6096 1.3208)
			(layers "F.Cu" "F.Mask" "F.Paste")
			(net "U271_1_ADD0")
		)
		(pad "8" smd rect
			(at 2.649982 -1.905 270)
			(size 0.6096 1.3208)
			(layers "F.Cu" "F.Mask" "F.Paste")
			(net "P3V3_AUX")
		)
	)
	(footprint ""
		(layer "F.Cu")
		(at 395.794738 -395.1732 90)
		(property "Reference" "R1100"
			(at 0 0 90)
			(layer "F.SilkS")
			(hide yes)
			(effects
				(font
					(size 1.27 1.27)
				)
			)
		)
		(property "Value" ""
			(at 0 0 90)
			(layer "F.Fab")
			(effects
				(font
					(size 1.27 1.27)
				)
			)
		)
		(duplicate_pad_numbers_are_jumpers no)
		(fp_line
			(start 0.32512 -0.175006)
			(end 0.32512 0.175006)
			(stroke
				(width 0.1)
				(type default)
			)
			(layer "F.Fab")
		)
		(fp_line
			(start -0.32512 -0.175006)
			(end 0.32512 -0.175006)
			(stroke
				(width 0.1)
				(type default)
			)
			(layer "F.Fab")
		)
		(fp_line
			(start 0.32512 0.175006)
			(end -0.32512 0.175006)
			(stroke
				(width 0.1)
				(type default)
			)
			(layer "F.Fab")
		)
		(fp_line
			(start -0.32512 0.175006)
			(end -0.32512 -0.175006)
			(stroke
				(width 0.1)
				(type default)
			)
			(layer "F.Fab")
		)
		(pad "1" smd rect
			(at -0.2667 0 90)
			(size 0.3048 0.381)
			(layers "F.Cu" "F.Mask" "F.Paste")
			(net "RT_CPU0_P3_ADDR2")
		)
		(pad "2" smd rect
			(at 0.2667 0 270)
			(size 0.3048 0.381)
			(layers "F.Cu" "F.Mask" "F.Paste")
			(net "GND")
		)
	)
	(footprint ""
		(layer "F.Cu")
		(at 391.291318 -74.375264 180)
		(property "Reference" "R1270"
			(at 0 0 180)
			(layer "F.SilkS")
			(hide yes)
			(effects
				(font
					(size 1.27 1.27)
				)
			)
		)
		(property "Value" ""
			(at 0 0 180)
			(layer "F.Fab")
			(effects
				(font
					(size 1.27 1.27)
				)
			)
		)
		(duplicate_pad_numbers_are_jumpers no)
		(fp_line
			(start 0.7874 0.4064)
			(end -0.7874 0.4064)
			(stroke
				(width 0.1524)
				(type default)
			)
			(layer "F.SilkS")
		)
		(fp_line
			(start 0.7874 -0.4064)
			(end 0.7874 0.4064)
			(stroke
				(width 0.1524)
				(type default)
			)
			(layer "F.SilkS")
		)
		(fp_line
			(start -0.7874 0.4064)
			(end -0.7874 -0.4064)
			(stroke
				(width 0.1524)
				(type default)
			)
			(layer "F.SilkS")
		)
		(fp_line
			(start -0.7874 -0.4064)
			(end 0.7874 -0.4064)
			(stroke
				(width 0.1524)
				(type default)
			)
			(layer "F.SilkS")
		)
		(fp_line
			(start 0.67945 0.3048)
			(end 0.120396 0.3048)
			(stroke
				(width 0.1)
				(type default)
			)
			(layer "F.Fab")
		)
		(fp_line
			(start 0.67945 -0.3048)
			(end 0.67945 0.3048)
			(stroke
				(width 0.1)
				(type default)
			)
			(layer "F.Fab")
		)
		(fp_line
			(start 0.12065 -0.2794)
			(end 0.12065 -0.3048)
			(stroke
				(width 0.1)
				(type default)
			)
			(layer "F.Fab")
		)
		(fp_line
			(start 0.12065 -0.3048)
			(end 0.67945 -0.3048)
			(stroke
				(width 0.1)
				(type default)
			)
			(layer "F.Fab")
		)
		(fp_line
			(start 0.120396 0.3048)
			(end 0.120396 0.2794)
			(stroke
				(width 0.1)
				(type default)
			)
			(layer "F.Fab")
		)
		(fp_line
			(start 0.120396 0.2794)
			(end -0.12065 0.2794)
			(stroke
				(width 0.1)
				(type default)
			)
			(layer "F.Fab")
		)
		(fp_line
			(start -0.12065 0.3048)
			(end -0.67945 0.3048)
			(stroke
				(width 0.1)
				(type default)
			)
			(layer "F.Fab")
		)
		(fp_line
			(start -0.12065 0.2794)
			(end -0.12065 0.3048)
			(stroke
				(width 0.1)
				(type default)
			)
			(layer "F.Fab")
		)
		(fp_line
			(start -0.12065 -0.2794)
			(end 0.12065 -0.2794)
			(stroke
				(width 0.1)
				(type default)
			)
			(layer "F.Fab")
		)
		(fp_line
			(start -0.12065 -0.305054)
			(end -0.12065 -0.2794)
			(stroke
				(width 0.1)
				(type default)
			)
			(layer "F.Fab")
		)
		(fp_line
			(start -0.67945 0.3048)
			(end -0.67945 -0.305054)
			(stroke
				(width 0.1)
				(type default)
			)
			(layer "F.Fab")
		)
		(fp_line
			(start -0.67945 -0.305054)
			(end -0.12065 -0.305054)
			(stroke
				(width 0.1)
				(type default)
			)
			(layer "F.Fab")
		)
		(pad "1" smd circle
			(at -0.40005 0 180)
			(size 0 0)
			(layers "F.Cu" "F.Mask" "F.Paste")
			(net "P12V_OCP_SFF_ADC_ALERT_R")
		)
		(pad "2" smd circle
			(at 0.40005 0 180)
			(size 0 0)
			(layers "F.Cu" "F.Mask" "F.Paste")
			(net "OCP_SFF_P3V3_P12V_ADC_R_ALERT")
		)
	)
)
